FILE_TYPE = CONNECTIVITY;
{Allegro Design Entry HDL 17.2-2016 S081 (4005846) 1/11/2022}
"PAGE_NUMBER" = 276;
0"NC";
1"PVCCFA_EHV_FIVRA_CPU1_PVCC2\g";
2"PVCCFA_EHV_FIVRA_CPU1_PVCC1\g";
3"PVCCFA_EHV_FIVRA_CPU1\g";
4"SW_P12V_PVCCFA_EHV_FIVRA_CPU1_L\g";
5"SW_P12V_PVCCFA_EHV_FIVRA_CPU1_R\g";
6"P12V_AUX\g";
7"PVCCFA_EHV_FIVRA_CPU1\g";
8"PVCCFA_EHV_FIVRA_CPU1\g";
9"SW_P12V_PVCCFA_EHV_FIVRA_CPU1_R\g";
10"GND\g";
11"GND\g";
12"GND\g";
13"GND\g";
14"GND\g";
15"GND\g";
16"GND\g";
17"GND\g";
18"GND\g";
19"GND\g";
20"GND\g";
21"GND\g";
22"GND\g";
23"GND\g";
24"GND\g";
25"GND\g";
26"GND\g";
27"PVCCFA_EHV_FIVRA_CPU1_VOS3";
28"SW_PVCCFA_EHV_FIVRA_CPU1_BOOTR3";
29"SW_PVCCFA_EHV_FIVRA_CPU1_SW3";
30"SW_PVCCFA_EHV_FIVRA_CPU1_SW4";
31"PVCCFA_EHV_FIVRA_CPU1_VOS4";
32"SW_PVCCFA_EHV_FIVRA_CPU1_BOOT4_R";
33"SW_PVCCFA_EHV_FIVRA_CPU1_BOOT3_R";
34"SW_PVCCFA_EHV_FIVRA_CPU1_BOOTR4";
35"SW_PVCCFA_EHV_FIVRA_CPU1_BOOT3";
36"PVCCFA_EHV_FIVRA_CPU1_VDD3"CDS_PHYS_NET_NAME"PVCCFA_EHV_FIVRA_CPU1_VDD3";
37"PVCCFA_EHV_FIVRA_CPU1_IMON3";
38"PVCCIN_CPU1_VREF";
39"PVCCFA_EHV_FIVRA_CPU1_BTSEN";
40"PVCCFA_EHV_FIVRA_CPU1_PWM3";
41"PVCCFA_EHV_FIVRA_CPU1_VDD4"CDS_PHYS_NET_NAME"PVCCFA_EHV_FIVRA_CPU1_VDD4";
42"SW_PVCCFA_EHV_FIVRA_CPU1_BOOT4";
43"PVCCFA_EHV_FIVRA_CPU1_PWM4";
44"PVCCFA_EHV_FIVRA_CPU1_BTSEN";
45"PVCCFA_EHV_FIVRA_CPU1_IMON4";
46"PVCCIN_CPU1_VREF";
47"PVCCFA_EHV_FIVRA_CPU1_LSET3";
48"PVCCFA_EHV_FIVRA_CPU1_LSET4";
%"UNIVERSAL_GND"
"1","(-7825,3100)","0","logical_power","I1";
;
HDL_POWER"GND"
CDS_LIB"logical_power";
"A"10;
%"UNIVERSAL_GND"
"1","(-7325,4025)","0","logical_power","I11";
;
HDL_POWER"GND"
CDS_LIB"logical_power";
"A"14;
%"Q_CAP"
"1","(-7325,4275)","0","pure_quanta","I12";
;
PART_NUMBER"CH5222KEB01"
MATERIAL"X6S"
PACK_TYPE"C0402"
TOLERANCE"10%"
VALUE"2.2UF"
VOLTAGE"10V"
LOCATION"PC1192"
CDS_LIB"pure_quanta"
LOCATION"PC1192"
$SEC"1"
CDS_SEC"1";
"B"
$PN"2"14;
"A"
$PN"1"41;
%"Q_CAP"
"2","(-7050,3625)","0","pure_quanta","I13";
;
PART_NUMBER"CH4104K1B00"
MATERIAL"X7R"
VOLTAGE"25V"
PACK_TYPE"0402"
VALUE"0.1UF"
TOLERANCE"10%"
LOCATION"PC1370"
CDS_LIB"pure_quanta"
$SEC"1"
CDS_SEC"1";
"A"
$PN"1"11;
"B"
$PN"2"46;
%"UNIVERSAL_GND"
"1","(-6800,4425)","0","logical_power","I14";
;
HDL_POWER"GND"
CDS_LIB"logical_power";
"A"15;
%"ISL99390FRZTR5935"
"1","(-5800,3825)","0","pure_quanta","I15";
;
PART_NUMBER"AL099390004"
MATERIAL"IC"
VALUE"ISL99390FRZ-TR5935"
PART_TYPE"SMLF"
LOCATION"PU78_P1_4"
NEEDS_NO_SIZE"TRUE"
CDS_LMAN_SYM_OUTLINE"-300,700,250,-650"
CDS_LIB"pure_quanta"
$SEC"1"
CDS_SEC"1";
"PGND2"
$PN"7_9-20_24"16;
"GL2"
$PN"41"0;
"GL1"
$PN"6"0;
"DNC"
$PN"31"0;
"EN"
$PN"35"41;
"PGND3"
$PN"40"16;
"VOS"
$PN"1"31;
"VIN2"
$PN"30"4;
"PGND1"
$PN"5"16;
"SW"
$PN"10_19"30;
"LSET"
$PN"37"48;
"IOUT"
$PN"38"45;
"TOUT_FLT"
$PN"36"44;
"PVCC"
$PN"4"1;
"PHASE"
$PN"32"34;
"VIN1"
$PN"25_29"4;
"BOOT"
$PN"33"42;
"AGND"
$PN"2"16;
"VCC"
$PN"3"41;
"REFIN"
$PN"39"46;
"PWM"
$PN"34"43;
%"UNIVERSAL_GND"
"1","(-5150,3100)","0","logical_power","I16";
;
HDL_POWER"GND"
CDS_LIB"logical_power";
"A"16;
%"Q_RES"
"1","(-4300,4275)","0","pure_quanta","I17";
;
PART_NUMBER"CS-3302FB01"
WATTAGE"1/16W"
TOLERANCE"1%"
MATERIAL"CHIP"
PACK_TYPE"0402LF"
VALUE"3.3"
LOCATION"PR1803"
CDS_LIB"pure_quanta"
$SEC"1"
CDS_SEC"1";
"B"
$PN"2"32;
"A"
$PN"1"42;
%"Q_RES"
"2","(-7325,4675)","0","pure_quanta","I18";
;
PART_NUMBER"CS-2202FB01"
MATERIAL"CHIP"
VALUE"2.2"
TOLERANCE"1%"
WATTAGE"1/16W"
PACK_TYPE"0402LF"
LOCATION"PR1307"
CDS_LIB"pure_quanta"
$SEC"1"
CDS_SEC"1";
"A"
$PN"1"1;
"B"
$PN"2"41;
%"VCC15"
"1","(-7325,5000)","0","logical_power","I19";
;
HDL_POWER"PVCCFA_EHV_FIVRA_CPU1_PVCC2"
CDS_LIB"logical_power";
"A"1;
%"Q_RES"
"2","(-7825,3325)","2","pure_quanta","I2";
;
PART_NUMBER"CS28872FB01"
WATTAGE"1/16W"
MATERIAL"EMPTY"
TOLERANCE"1%"
VALUE"8.87K"
PACK_TYPE"0402LF"
LOCATION"PR1304"
CDS_LIB"pure_quanta"
LOCATION"PR1304"
$SEC"1"
CDS_SEC"1";
"A"
$PN"1"48;
"B"
$PN"2"10;
%"Q_CAP"
"1","(-6800,4675)","0","pure_quanta","I20";
;
PART_NUMBER"CH5222KEB01"
VALUE"2.2UF"
MATERIAL"X6S"
PACK_TYPE"C0402"
VOLTAGE"10V"
TOLERANCE"10%"
LOCATION"PC1245_P1_4"
CDS_LIB"pure_quanta"
$SEC"1"
CDS_SEC"1";
"B"
$PN"2"15;
"A"
$PN"1"1;
%"Q_CAP"
"2","(-7050,6425)","0","pure_quanta","I23";
;
PART_NUMBER"CH4104K1B00"
PACK_TYPE"0402"
TOLERANCE"10%"
MATERIAL"X7R"
VOLTAGE"25V"
VALUE"0.1UF"
LOCATION"PC1369"
CDS_LIB"pure_quanta"
$SEC"1"
CDS_SEC"1";
"A"
$PN"1"13;
"B"
$PN"2"38;
%"ISL99390FRZTR5935"
"1","(-5800,6625)","0","pure_quanta","I24";
;
PART_NUMBER"AL099390004"
MATERIAL"IC"
PART_TYPE"SMLF"
VALUE"ISL99390FRZ-TR5935"
LOCATION"PU77_P1_3"
NEEDS_NO_SIZE"TRUE"
CDS_LMAN_SYM_OUTLINE"-300,700,250,-650"
CDS_LIB"pure_quanta"
$SEC"1"
CDS_SEC"1";
"PGND2"
$PN"7_9-20_24"19;
"GL2"
$PN"41"0;
"GL1"
$PN"6"0;
"DNC"
$PN"31"0;
"EN"
$PN"35"36;
"PGND3"
$PN"40"19;
"VOS"
$PN"1"27;
"VIN2"
$PN"30"5;
"PGND1"
$PN"5"19;
"SW"
$PN"10_19"29;
"LSET"
$PN"37"47;
"IOUT"
$PN"38"37;
"TOUT_FLT"
$PN"36"39;
"PVCC"
$PN"4"2;
"PHASE"
$PN"32"28;
"VIN1"
$PN"25_29"5;
"BOOT"
$PN"33"35;
"AGND"
$PN"2"19;
"VCC"
$PN"3"36;
"REFIN"
$PN"39"38;
"PWM"
$PN"34"40;
%"Q_CAP"
"1","(-7325,7075)","0","pure_quanta","I27";
;
PART_NUMBER"CH5222KEB01"
MATERIAL"X6S"
VOLTAGE"10V"
VALUE"2.2UF"
TOLERANCE"10%"
PACK_TYPE"C0402"
LOCATION"PC1191"
CDS_LIB"pure_quanta"
$SEC"1"
CDS_SEC"1";
"B"
$PN"2"17;
"A"
$PN"1"36;
%"UNIVERSAL_GND"
"1","(-7325,6825)","0","logical_power","I28";
;
HDL_POWER"GND"
CDS_LIB"logical_power";
"A"17;
%"Q_RES"
"2","(-7325,7475)","0","pure_quanta","I29";
;
PART_NUMBER"CS-2202FB01"
MATERIAL"CHIP"
WATTAGE"1/16W"
PACK_TYPE"0402LF"
TOLERANCE"1%"
VALUE"2.2"
LOCATION"PR1306"
CDS_LIB"pure_quanta"
$SEC"1"
CDS_SEC"1";
"A"
$PN"1"2;
"B"
$PN"2"36;
%"UNIVERSAL_GND"
"1","(-7875,3525)","0","logical_power","I3";
;
HDL_POWER"GND"
CDS_LIB"logical_power";
"A"11;
%"UNIVERSAL_GND"
"1","(-6800,7225)","0","logical_power","I30";
;
HDL_POWER"GND"
CDS_LIB"logical_power";
"A"18;
%"Q_CAP"
"1","(-6800,7475)","0","pure_quanta","I31";
;
PART_NUMBER"CH5222KEB01"
MATERIAL"X6S"
PACK_TYPE"C0402"
VALUE"2.2UF"
TOLERANCE"10%"
VOLTAGE"10V"
LOCATION"PC1244_P1_3"
CDS_LIB"pure_quanta"
$SEC"1"
CDS_SEC"1";
"B"
$PN"2"18;
"A"
$PN"1"2;
%"VCC15"
"1","(-7325,7800)","0","logical_power","I32";
;
HDL_POWER"PVCCFA_EHV_FIVRA_CPU1_PVCC1"
CDS_LIB"logical_power";
"A"2;
%"Q_CAP"
"1","(-5000,4725)","0","pure_quanta","I33";
;
PART_NUMBER"TMP_QCH2336K1B12"
VOLTAGE"50V"
PACK_TYPE"0402"
MATERIAL"X7R"
TOLERANCE"10%"
VALUE"3300PF"
LOCATION"PC1194_P1_4"
CDS_LIB"pure_quanta"
LOCATION"PC1194_P1_4"
$SEC"1"
CDS_SEC"1";
"B"
$PN"2"20;
"A"
$PN"1"4;
%"UNIVERSAL_GND"
"1","(-5150,5900)","0","logical_power","I34";
;
HDL_POWER"GND"
CDS_LIB"logical_power";
"A"19;
%"Q_CAP"
"1","(-4600,4725)","0","pure_quanta","I35";
;
PART_NUMBER"CH5103KEB01"
VOLTAGE"16V"
TOLERANCE"10%"
PACK_TYPE"C0402"
MATERIAL"X6S"
VALUE"1UF"
LOCATION"PC1196_P1_4"
CDS_LIB"pure_quanta"
LOCATION"PC1196_P1_4"
$SEC"1"
CDS_SEC"1";
"B"
$PN"2"20;
"A"
$PN"1"4;
%"Q_CAP"
"1","(-4200,4725)","0","pure_quanta","I36";
;
PART_NUMBER"CH6223MEA01"
TOLERANCE"20%"
MATERIAL"X6S"
VALUE"22UF"
PACK_TYPE"C0805"
VOLTAGE"16V"
LOCATION"PC1200_P1_4"
CDS_LIB"pure_quanta"
LOCATION"PC1200_P1_4"
$SEC"1"
CDS_SEC"1";
"B"
$PN"2"20;
"A"
$PN"1"4;
%"Q_CAP"
"1","(-3800,4725)","0","pure_quanta","I37";
;
PART_NUMBER"CH6223MEA01"
TOLERANCE"20%"
VALUE"22UF"
PACK_TYPE"C0805"
VOLTAGE"16V"
MATERIAL"X6S"
LOCATION"PC1202_P1_4"
CDS_LIB"pure_quanta"
LOCATION"PC1202_P1_4"
$SEC"1"
CDS_SEC"1";
"B"
$PN"2"20;
"A"
$PN"1"4;
%"Q_CAP"
"1","(-5000,7525)","0","pure_quanta","I38";
;
PART_NUMBER"TMP_QCH2336K1B12"
MATERIAL"X7R"
PACK_TYPE"0402"
TOLERANCE"10%"
VOLTAGE"50V"
VALUE"3300PF"
LOCATION"PC1193_P1_3"
CDS_LIB"pure_quanta"
LOCATION"PC1193_P1_3"
$SEC"1"
CDS_SEC"1";
"B"
$PN"2"22;
"A"
$PN"1"5;
%"Q_CAP"
"1","(-4600,7525)","0","pure_quanta","I39";
;
PART_NUMBER"CH5103KEB01"
MATERIAL"X6S"
VALUE"1UF"
TOLERANCE"10%"
PACK_TYPE"C0402"
VOLTAGE"16V"
LOCATION"PC1195_P1_3"
CDS_LIB"pure_quanta"
LOCATION"PC1195_P1_3"
$SEC"1"
CDS_SEC"1";
"B"
$PN"2"22;
"A"
$PN"1"5;
%"UNIVERSAL_GND"
"1","(-7800,5900)","0","logical_power","I4";
;
HDL_POWER"GND"
CDS_LIB"logical_power";
"A"12;
%"Q_RES"
"1","(-4300,7075)","0","pure_quanta","I40";
;
PART_NUMBER"CS-3302FB01"
WATTAGE"1/16W"
TOLERANCE"1%"
PACK_TYPE"0402LF"
VALUE"3.3"
MATERIAL"CHIP"
LOCATION"PR1802"
CDS_LIB"pure_quanta"
$SEC"1"
CDS_SEC"1";
"B"
$PN"2"33;
"A"
$PN"1"35;
%"Q_CAP"
"1","(-4200,7525)","0","pure_quanta","I41";
;
PART_NUMBER"CH6223MEA01"
TOLERANCE"20%"
PACK_TYPE"C0805"
MATERIAL"X6S"
VALUE"22UF"
VOLTAGE"16V"
LOCATION"PC1199_P1_3"
CDS_LIB"pure_quanta"
LOCATION"PC1199_P1_3"
$SEC"1"
CDS_SEC"1";
"B"
$PN"2"22;
"A"
$PN"1"5;
%"Q_CAP"
"1","(-3800,7525)","0","pure_quanta","I42";
;
PART_NUMBER"CH6223MEA01"
TOLERANCE"20%"
VALUE"22UF"
VOLTAGE"16V"
MATERIAL"X6S"
PACK_TYPE"C0805"
LOCATION"PC1201_P1_3"
CDS_LIB"pure_quanta"
LOCATION"PC1201_P1_3"
$SEC"1"
CDS_SEC"1";
"B"
$PN"2"22;
"A"
$PN"1"5;
%"Q_RES"
"1","(-3100,3575)","0","pure_quanta","I43";
;
PART_NUMBER"CS00002JB13"
MATERIAL"CHIP"
PACK_TYPE"0402LF"
WATTAGE"1/16W"
VALUE"0"
TOLERANCE"5%"
LOCATION"PR1334"
CDS_LIB"pure_quanta"
$SEC"1"
CDS_SEC"1";
"B"
$PN"2"3;
"A"
$PN"1"31;
%"Q_INDUCTOR"
"1","(-3100,3850)","0","pure_quanta","I44";
;
PART_NUMBER"CV+13^0KZ11"
PACK_TYPE"SMLF"
VALUE"130NH/106A"
MATERIAL"IND"
LOCATION"PL113"
NEEDS_NO_SIZE"TRUE"
CDS_LIB"pure_quanta"
$SEC"1"
CDS_SEC"1";
"1"
$PN"1"30;
"2"
$PN"2"3;
%"Q_CAP"
"1","(-3375,4100)","2","pure_quanta","I45";
;
PART_NUMBER"CH4106K1B01"
TOLERANCE"10%"
VALUE"100NF"
VOLTAGE"50V"
PACK_TYPE"C0402"
MATERIAL"X7R"
LOCATION"PC1198"
CDS_LIB"pure_quanta"
$SEC"1"
CDS_SEC"1";
"B"
$PN"2"34;
"A"
$PN"1"32;
%"UNIVERSAL_GND"
"1","(-3200,4350)","0","logical_power","I46";
;
HDL_POWER"GND"
CDS_LIB"logical_power";
"A"20;
%"Q_CAP"
"1","(-2150,3625)","0","pure_quanta","I47";
;
PART_NUMBER"CH4106K1B01"
MATERIAL"X7R"
PACK_TYPE"C0402"
TOLERANCE"10%"
VOLTAGE"50V"
VALUE"100NF"
LOCATION"PC1203_P1_4"
CDS_LIB"pure_quanta"
LOCATION"PC1203_P1_4"
$SEC"1"
CDS_SEC"1";
"B"
$PN"2"21;
"A"
$PN"1"3;
%"Q_CAP"
"1","(-1625,3625)","0","pure_quanta","I48";
;
PART_NUMBER"CH622KMEA03"
TOLERANCE"20%"
PACK_TYPE"C0805"
VOLTAGE"4V"
MATERIAL"X6S"
VALUE"22UF"
LOCATION"PC1207_P1_4"
CDS_LIB"pure_quanta"
LOCATION"PC1207_P1_4"
$SEC"1"
CDS_SEC"1";
"B"
$PN"2"21;
"A"
$PN"1"3;
%"UNIVERSAL_GND"
"1","(-900,3250)","0","logical_power","I49";
;
HDL_POWER"GND"
CDS_LIB"logical_power";
"A"21;
%"Q_RES"
"2","(-7800,6125)","2","pure_quanta","I5";
;
PART_NUMBER"CS28872FB01"
PACK_TYPE"0402LF"
VALUE"8.87K"
TOLERANCE"1%"
WATTAGE"1/16W"
MATERIAL"EMPTY"
LOCATION"PR1305"
CDS_LIB"pure_quanta"
LOCATION"PR1305"
$SEC"1"
CDS_SEC"1";
"A"
$PN"1"47;
"B"
$PN"2"12;
%"Q_CAP"
"1","(-1200,3625)","0","pure_quanta","I50";
;
PART_NUMBER"CH622KMEA03"
TOLERANCE"20%"
PACK_TYPE"C0805"
VOLTAGE"4V"
MATERIAL"X6S"
VALUE"22UF"
LOCATION"PC1209_P1_4"
CDS_LIB"pure_quanta"
LOCATION"PC1209_P1_4"
$SEC"1"
CDS_SEC"1";
"B"
$PN"2"21;
"A"
$PN"1"3;
%"VCC15"
"1","(-900,4025)","0","logical_power","I51";
;
HDL_POWER"PVCCFA_EHV_FIVRA_CPU1"
CDS_LIB"logical_power";
"A"3;
%"Q_CAP"
"1","(-3350,4725)","0","pure_quanta","I52";
;
PART_NUMBER"CH6223MEA01"
TOLERANCE"20%"
MATERIAL"X6S"
PACK_TYPE"C0805"
VOLTAGE"16V"
VALUE"22UF"
LOCATION"PC727_P1_4"
CDS_LIB"pure_quanta"
$SEC"1"
CDS_SEC"1";
"B"
$PN"2"20;
"A"
$PN"1"4;
%"VCC15"
"1","(-3200,5100)","0","logical_power","I53";
;
HDL_POWER"SW_P12V_PVCCFA_EHV_FIVRA_CPU1_L"
CDS_LIB"logical_power";
"A"4;
%"Q_RES"
"1","(-3100,6375)","0","pure_quanta","I54";
;
PART_NUMBER"CS00002JB13"
MATERIAL"CHIP"
TOLERANCE"5%"
VALUE"0"
WATTAGE"1/16W"
PACK_TYPE"0402LF"
LOCATION"PR1333"
CDS_LIB"pure_quanta"
$SEC"1"
CDS_SEC"1";
"B"
$PN"2"8;
"A"
$PN"1"27;
%"Q_CAPP"
"1","(-1625,5175)","0","pure_quanta","I55";
;
PART_NUMBER"CC7560JMD16"
PACK_TYPE"THLF"
VALUE"560UF"
TOLERANCE"20%"
MATERIAL"OSCON"
VOLTAGE"2.5V"
LOCATION"PC1201"
CDS_LIB"pure_quanta"
$SEC"1"
CDS_SEC"1";
"A"
$PN"1"7;
"B"
$PN"2"25;
%"Q_CAP"
"1","(-2050,6425)","0","pure_quanta","I56";
;
PART_NUMBER"CH5103KEB01"
PACK_TYPE"C0402"
VALUE"1UF"
MATERIAL"X6S"
TOLERANCE"10%"
VOLTAGE"16V"
LOCATION"PC1204_P1_3"
CDS_LIB"pure_quanta"
LOCATION"PC1204_P1_3"
$SEC"1"
CDS_SEC"1";
"B"
$PN"2"24;
"A"
$PN"1"8;
%"Q_INDUCTOR"
"1","(-3100,6650)","0","pure_quanta","I57";
;
PART_NUMBER"CV+13^0KZ11"
MATERIAL"IND"
VALUE"130NH/106A"
PACK_TYPE"SMLF"
LOCATION"PL12"
CDS_LIB"pure_quanta"
NEEDS_NO_SIZE"TRUE"
$SEC"1"
CDS_SEC"1";
"1"
$PN"1"29;
"2"
$PN"2"8;
%"Q_CAP"
"1","(-3375,6900)","2","pure_quanta","I58";
;
PART_NUMBER"CH4106K1B01"
MATERIAL"X7R"
VALUE"100NF"
VOLTAGE"50V"
TOLERANCE"10%"
PACK_TYPE"C0402"
LOCATION"PC1197"
CDS_LIB"pure_quanta"
$SEC"1"
CDS_SEC"1";
"B"
$PN"2"28;
"A"
$PN"1"33;
%"UNIVERSAL_GND"
"1","(-3200,7175)","0","logical_power","I59";
;
HDL_POWER"GND"
CDS_LIB"logical_power";
"A"22;
%"UNIVERSAL_GND"
"1","(-7875,6325)","0","logical_power","I6";
;
HDL_POWER"GND"
CDS_LIB"logical_power";
"A"13;
%"Q_CAP"
"1","(-3350,7525)","0","pure_quanta","I60";
;
PART_NUMBER"CH6223MEA01"
TOLERANCE"20%"
VOLTAGE"16V"
PACK_TYPE"C0805"
VALUE"22UF"
MATERIAL"X6S"
LOCATION"PC726_P1_3"
CDS_LIB"pure_quanta"
$SEC"1"
CDS_SEC"1";
"B"
$PN"2"22;
"A"
$PN"1"5;
%"VCC15"
"1","(-3200,7900)","0","logical_power","I61";
;
HDL_POWER"SW_P12V_PVCCFA_EHV_FIVRA_CPU1_R"
CDS_LIB"logical_power";
"A"5;
%"Q_CAP"
"1","(-2075,7300)","0","pure_quanta","I62";
;
PART_NUMBER"CH4106K1B01"
VOLTAGE"50V"
VALUE"100NF"
TOLERANCE"10%"
MATERIAL"X7R"
PACK_TYPE"C0402"
LOCATION"PC1658"
CDS_LIB"pure_quanta"
$SEC"1"
CDS_SEC"1";
"B"
$PN"2"23;
"A"
$PN"1"6;
%"GND"
"1","(-2075,7050)","0","logical_power","I63";
;
HDL_POWER"GND"
CDS_LIB"logical_power"
SIZE"1B";
"A<SIZE-1..0>\NAC"23;
%"Q_INDUCTOR"
"1","(-1650,7525)","0","pure_quanta","I64";
;
PART_NUMBER"CV+10G0MZ04"
PACK_TYPE"SMLF"
MATERIAL"IND"
VALUE"100NH/16A"
LOCATION"PL14"
NEEDS_NO_SIZE"TRUE"
CDS_LIB"pure_quanta"
$SEC"1"
CDS_SEC"1";
"1"
$PN"1"6;
"2"
$PN"2"9;
%"VCC15"
"1","(-2075,7675)","0","logical_power","I65";
;
HDL_POWER"P12V_AUX"
CDS_LIB"logical_power";
"A"6;
%"Q_CAP"
"1","(-1625,6425)","0","pure_quanta","I66";
;
PART_NUMBER"CH622KMEA03"
TOLERANCE"20%"
PACK_TYPE"C0805"
VALUE"22UF"
MATERIAL"X6S"
VOLTAGE"4V"
LOCATION"PC1206_P1_3"
CDS_LIB"pure_quanta"
LOCATION"PC1206_P1_3"
$SEC"1"
CDS_SEC"1";
"B"
$PN"2"24;
"A"
$PN"1"8;
%"Q_CAPP"
"1","(-1100,5175)","0","pure_quanta","I67";
;
PART_NUMBER"CC7560JMD16"
PACK_TYPE"THLF"
VALUE"560UF"
TOLERANCE"20%"
MATERIAL"OSCON"
VOLTAGE"2.5V"
LOCATION"PC1203"
CDS_LIB"pure_quanta"
$SEC"1"
CDS_SEC"1";
"A"
$PN"1"7;
"B"
$PN"2"25;
%"Q_CAP"
"1","(-1200,6425)","0","pure_quanta","I68";
;
PART_NUMBER"CH622KMEA03"
TOLERANCE"20%"
PACK_TYPE"C0805"
VALUE"22UF"
VOLTAGE"4V"
MATERIAL"X6S"
LOCATION"PC1208_P1_3"
CDS_LIB"pure_quanta"
LOCATION"PC1208_P1_3"
$SEC"1"
CDS_SEC"1";
"B"
$PN"2"24;
"A"
$PN"1"8;
%"UNIVERSAL_GND"
"1","(-900,6050)","0","logical_power","I69";
;
HDL_POWER"GND"
CDS_LIB"logical_power";
"A"24;
%"Q_CAPP"
"1","(-575,5175)","0","pure_quanta","I70";
;
PART_NUMBER"CC7560JMD16"
PACK_TYPE"THLF"
VALUE"560UF"
TOLERANCE"20%"
MATERIAL"OSCON"
VOLTAGE"2.5V"
LOCATION"PC1204"
CDS_LIB"pure_quanta"
$SEC"1"
CDS_SEC"1";
"A"
$PN"1"7;
"B"
$PN"2"25;
%"UNIVERSAL_GND"
"1","(375,4825)","0","logical_power","I71";
;
HDL_POWER"GND"
CDS_LIB"logical_power";
"A"25;
%"Q_CAPP"
"1","(-75,5175)","0","pure_quanta","I72";
;
PART_NUMBER"CH733LY8802"
VOLTAGE"2.5V"
MATERIAL"SPCAP"
TOLERANCE"+10/-35%"
VALUE"330UF"
PACK_TYPE"SMLF"
LOCATION"PC1205"
CDS_LIB"pure_quanta"
$SEC"1"
CDS_SEC"1";
"A"
$PN"1"7;
"B"
$PN"2"25;
%"Q_CAPP"
"1","(375,5175)","0","pure_quanta","I73";
;
PART_NUMBER"CH733LY8802"
VOLTAGE"2.5V"
PACK_TYPE"SMLF"
MATERIAL"SPCAP"
VALUE"330UF"
TOLERANCE"+10/-35%"
LOCATION"PC2171"
CDS_LIB"pure_quanta"
$SEC"1"
CDS_SEC"1";
"A"
$PN"1"7;
"B"
$PN"2"25;
%"VCC15"
"1","(375,5500)","0","logical_power","I74";
;
HDL_POWER"PVCCFA_EHV_FIVRA_CPU1"
CDS_LIB"logical_power";
"A"7;
%"Q_CAP"
"1","(-1275,7275)","0","pure_quanta","I75";
;
PART_NUMBER"CH6223MEA01"
TOLERANCE"20%"
MATERIAL"X6S"
VALUE"22UF"
VOLTAGE"16V"
PACK_TYPE"C0805"
LOCATION"PC1681"
CDS_LIB"pure_quanta"
$SEC"1"
CDS_SEC"1";
"B"
$PN"2"26;
"A"
$PN"1"9;
%"VCC15"
"1","(-900,6825)","0","logical_power","I76";
;
HDL_POWER"PVCCFA_EHV_FIVRA_CPU1"
CDS_LIB"logical_power";
"A"8;
%"Q_CAP"
"1","(-975,7275)","0","pure_quanta","I77";
;
PART_NUMBER"CH6223MEA01"
TOLERANCE"20%"
PACK_TYPE"C0805"
VOLTAGE"16V"
VALUE"22UF"
MATERIAL"X6S"
LOCATION"PC1682"
CDS_LIB"pure_quanta"
$SEC"1"
CDS_SEC"1";
"B"
$PN"2"26;
"A"
$PN"1"9;
%"Q_CAP"
"1","(-700,7275)","0","pure_quanta","I78";
;
PART_NUMBER"CH6223MEA01"
TOLERANCE"20%"
PACK_TYPE"C0805"
VOLTAGE"16V"
MATERIAL"X6S"
VALUE"22UF"
LOCATION"PC1683"
CDS_LIB"pure_quanta"
$SEC"1"
CDS_SEC"1";
"B"
$PN"2"26;
"A"
$PN"1"9;
%"UNIVERSAL_GND"
"1","(-150,6950)","0","logical_power","I79";
;
HDL_POWER"GND"
CDS_LIB"logical_power";
"A"26;
%"Q_CAP"
"1","(-425,7275)","0","pure_quanta","I80";
;
PART_NUMBER"CH6223MEA01"
TOLERANCE"20%"
VALUE"22UF"
VOLTAGE"16V"
MATERIAL"X6S"
PACK_TYPE"C0805"
LOCATION"PC1684"
CDS_LIB"pure_quanta"
$SEC"1"
CDS_SEC"1";
"B"
$PN"2"26;
"A"
$PN"1"9;
%"Q_CAPP"
"1","(-150,7275)","0","pure_quanta","I81";
;
PART_NUMBER"CC72703MD38"
PACK_TYPE"THLF"
TOLERANCE"20%"
MATERIAL"OSCON"
VALUE"270UF"
VOLTAGE"16V"
LOCATION"PC1210"
CDS_LIB"pure_quanta"
LOCATION"PC1210"
$SEC"1"
CDS_SEC"1";
"A"
$PN"1"9;
"B"
$PN"2"26;
%"VCC15"
"1","(-50,7650)","0","logical_power","I82";
;
HDL_POWER"SW_P12V_PVCCFA_EHV_FIVRA_CPU1_R"
CDS_LIB"logical_power";
"A"9;
END.
